(kicad_pcb
	(version 20241229)
	(generator "pcbnew")
	(generator_version "9.0")
	(general
		(thickness 1.6296)
		(legacy_teardrops no)
	)
	(paper "A3")
	(title_block
		(title "Thunderbolt to 10GbE adapter")
		(date "2026-04-21")
		(rev "1.1.0")
		(company "Antmicro Ltd")
		(comment 1 "www.antmicro.com")
		(comment 9 "footprints 205-209 of 703")
	)
	(layers
		(0 "F.Cu" signal)
		(4 "In1.Cu" signal)
		(6 "In2.Cu" signal)
		(8 "In3.Cu" signal)
		(10 "In4.Cu" signal)
		(12 "In5.Cu" signal)
		(14 "In6.Cu" signal)
		(2 "B.Cu" signal)
		(9 "F.Adhes" user "F.Adhesive")
		(11 "B.Adhes" user "B.Adhesive")
		(13 "F.Paste" user)
		(15 "B.Paste" user)
		(5 "F.SilkS" user "F.Silkscreen")
		(7 "B.SilkS" user "B.Silkscreen")
		(1 "F.Mask" user)
		(3 "B.Mask" user)
		(17 "Dwgs.User" user "User.Drawings")
		(19 "Cmts.User" user "User.Comments")
		(21 "Eco1.User" user "User.Eco1")
		(23 "Eco2.User" user "User.Eco2")
		(25 "Edge.Cuts" user)
		(27 "Margin" user)
		(31 "F.CrtYd" user "F.Courtyard")
		(29 "B.CrtYd" user "B.Courtyard")
		(35 "F.Fab" user)
		(33 "B.Fab" user)
	)
	(footprint "antmicro-footprints:R_0603_1608Metric"
		(layer "F.Cu")
		(at 150.500001 103.05 90)
		(descr "Resistor SMD 0603")
		(tags "resistor SMD 0603")
		(property "Reference" "R110"
			(at -17.649996 14.449998 90)
			(layer "F.SilkS")
			(effects
				(font
					(size 0.7 0.7)
					(thickness 0.15)
				)
			)
		)
		(property "Value" "R_0R_22.4A_0603"
			(at 0 1.6 90)
			(layer "F.Fab")
			(effects
				(font
					(size 0.7 0.7)
					(thickness 0.15)
				)
				(justify left bottom)
			)
		)
		(property "Datasheet" "https://fscdn.rohm.com/en/products/databook/datasheet/passive/resistor/chip_resistor/pmr-jpw-e.pdf"
			(at 0 0 90)
			(layer "F.Fab")
			(hide yes)
			(effects
				(font
					(size 1.27 1.27)
					(thickness 0.15)
				)
			)
		)
		(property "Description" "SMD Chip Resistor"
			(at 0 0 90)
			(layer "F.Fab")
			(hide yes)
			(effects
				(font
					(size 1.27 1.27)
					(thickness 0.15)
				)
			)
		)
		(property "MPN" "PMR03EZPJ000"
			(at 0 0 90)
			(unlocked yes)
			(layer "F.Fab")
			(hide yes)
			(effects
				(font
					(size 1 1)
					(thickness 0.15)
				)
			)
		)
		(property "Manufacturer" "ROHM Semiconductor"
			(at 0 0 90)
			(unlocked yes)
			(layer "F.Fab")
			(hide yes)
			(effects
				(font
					(size 1 1)
					(thickness 0.15)
				)
			)
		)
		(property "Val" "0R"
			(at 0 0 90)
			(unlocked yes)
			(layer "F.Fab")
			(hide yes)
			(effects
				(font
					(size 1 1)
					(thickness 0.15)
				)
			)
		)
		(property "Max. Curr." "22.4A"
			(at 0 0 90)
			(unlocked yes)
			(layer "F.Fab")
			(hide yes)
			(effects
				(font
					(size 1 1)
					(thickness 0.15)
				)
			)
		)
		(property "Author" "Antmicro"
			(at 0 0 90)
			(unlocked yes)
			(layer "F.Fab")
			(hide yes)
			(effects
				(font
					(size 1 1)
					(thickness 0.15)
				)
			)
		)
		(property "License" "Apache-2.0"
			(at 0 0 90)
			(unlocked yes)
			(layer "F.Fab")
			(hide yes)
			(effects
				(font
					(size 1 1)
					(thickness 0.15)
				)
			)
		)
		(property "Tolerance" "template_tolerance"
			(at 0 0 90)
			(unlocked yes)
			(layer "F.Fab")
			(hide yes)
			(effects
				(font
					(size 1 1)
					(thickness 0.15)
				)
			)
		)
		(sheetname "/X710 DCDC converters/")
		(sheetfile "DCDC_converters_X710.kicad_sch")
		(attr smd)
		(fp_line
			(start -0.15 -0.4)
			(end 0.15 -0.4)
			(stroke
				(width 0.15)
				(type solid)
			)
			(layer "F.SilkS")
		)
		(fp_line
			(start -0.15 0.4)
			(end 0.15 0.4)
			(stroke
				(width 0.15)
				(type solid)
			)
			(layer "F.SilkS")
		)
		(fp_rect
			(start -1.25 -0.65)
			(end 1.25 0.65)
			(stroke
				(width 0.05)
				(type solid)
			)
			(fill no)
			(layer "F.CrtYd")
		)
		(fp_rect
			(start -0.8 -0.4)
			(end 0.8 0.4)
			(stroke
				(width 0.15)
				(type solid)
			)
			(fill no)
			(layer "F.Fab")
		)
		(fp_text user "Author: Antmicro"
			(at -1.25 4.9 90)
			(layer "F.Fab")
			(effects
				(font
					(size 0.7 0.7)
					(thickness 0.15)
				)
				(justify left bottom)
			)
		)
		(fp_text user "License: Apache-2.0"
			(at -1.25 5.9 90)
			(layer "F.Fab")
			(effects
				(font
					(size 0.7 0.7)
					(thickness 0.15)
				)
				(justify left bottom)
			)
		)
		(fp_text user "${REFERENCE}"
			(at -1.25 3.898 90)
			(layer "F.Fab")
			(effects
				(font
					(size 0.7 0.7)
					(thickness 0.15)
				)
				(justify left bottom)
			)
		)
		(pad "1" smd roundrect
			(at -0.7 0 90)
			(size 0.8 1)
			(layers "F.Cu" "F.Mask" "F.Paste")
			(roundrect_rratio 0.2)
			(net 338 "/X710 DCDC converters/+1V88_OUT")
			(pintype "passive")
		)
		(pad "2" smd roundrect
			(at 0.7 0 90)
			(size 0.8 1)
			(layers "F.Cu" "F.Mask" "F.Paste")
			(roundrect_rratio 0.2)
			(net 18 "+1V88")
			(pintype "passive")
		)
	)
	(footprint "antmicro-footprints:C_0805_2012Metric"
		(layer "F.Cu")
		(at 147.1 56.8 -90)
		(descr "Capacitor SMD 0805")
		(tags "capacitor SMD 0805")
		(property "Reference" "C318"
			(at 4.6 -0.65 270)
			(layer "F.SilkS")
			(effects
				(font
					(size 0.7 0.7)
					(thickness 0.15)
				)
				(justify left bottom)
			)
		)
		(property "Value" "C_22u_25V_0805"
			(at -2.055717 1.963152 270)
			(layer "F.Fab")
			(effects
				(font
					(size 0.7 0.7)
					(thickness 0.15)
				)
				(justify left bottom)
			)
		)
		(property "Datasheet" "https://product.samsungsem.com/mlcc/CL21A226MAYNNN.do"
			(at 0 0 270)
			(layer "F.Fab")
			(hide yes)
			(effects
				(font
					(size 1.27 1.27)
					(thickness 0.15)
				)
			)
		)
		(property "Description" "SMT Multilayer Ceramic Capacitor, 22uF, +/-20%, 25V, X5R, 0805 [2012 Metric]"
			(at 0 0 270)
			(layer "F.Fab")
			(hide yes)
			(effects
				(font
					(size 1.27 1.27)
					(thickness 0.15)
				)
			)
		)
		(property "MPN" "CL21A226MAYNNNE"
			(at 0 0 270)
			(unlocked yes)
			(layer "F.Fab")
			(hide yes)
			(effects
				(font
					(size 1 1)
					(thickness 0.15)
				)
			)
		)
		(property "Manufacturer" "Samsung Electro-Mechanics"
			(at 0 0 270)
			(unlocked yes)
			(layer "F.Fab")
			(hide yes)
			(effects
				(font
					(size 1 1)
					(thickness 0.15)
				)
			)
		)
		(property "License" "Apache-2.0"
			(at 0 0 270)
			(unlocked yes)
			(layer "F.Fab")
			(hide yes)
			(effects
				(font
					(size 1 1)
					(thickness 0.15)
				)
			)
		)
		(property "Author" "Antmicro"
			(at 0 0 270)
			(unlocked yes)
			(layer "F.Fab")
			(hide yes)
			(effects
				(font
					(size 1 1)
					(thickness 0.15)
				)
			)
		)
		(property "Val" "22u"
			(at 0 0 270)
			(unlocked yes)
			(layer "F.Fab")
			(hide yes)
			(effects
				(font
					(size 1 1)
					(thickness 0.15)
				)
			)
		)
		(property "Voltage" "25V"
			(at 0 0 270)
			(unlocked yes)
			(layer "F.Fab")
			(hide yes)
			(effects
				(font
					(size 1 1)
					(thickness 0.15)
				)
			)
		)
		(property "Dielectric" "X5R"
			(at 0 0 270)
			(unlocked yes)
			(layer "F.Fab")
			(hide yes)
			(effects
				(font
					(size 1 1)
					(thickness 0.15)
				)
			)
		)
		(property "Public" "False"
			(at 0 0 270)
			(unlocked yes)
			(layer "F.Fab")
			(hide yes)
			(effects
				(font
					(size 1 1)
					(thickness 0.15)
				)
			)
		)
		(sheetname "/Power input/")
		(sheetfile "power_input.kicad_sch")
		(attr smd)
		(fp_line
			(start -0.3 0.7)
			(end 0.3 0.7)
			(stroke
				(width 0.15)
				(type solid)
			)
			(layer "F.SilkS")
		)
		(fp_line
			(start -0.3 -0.7)
			(end 0.3 -0.7)
			(stroke
				(width 0.15)
				(type solid)
			)
			(layer "F.SilkS")
		)
		(fp_rect
			(start 1.95 -0.9)
			(end -1.95 0.9)
			(stroke
				(width 0.05)
				(type default)
			)
			(fill no)
			(layer "F.CrtYd")
		)
		(fp_rect
			(start -0.95 -0.675)
			(end 0.95 0.675)
			(stroke
				(width 0.15)
				(type solid)
			)
			(fill no)
			(layer "F.Fab")
		)
		(fp_text user "${REFERENCE}"
			(at -1.9 3.947 270)
			(layer "F.Fab")
			(effects
				(font
					(size 0.7 0.7)
					(thickness 0.15)
				)
				(justify left bottom)
			)
		)
		(fp_text user "License: Apache-2.0"
			(at -1.9 4.947 270)
			(layer "F.Fab")
			(effects
				(font
					(size 0.7 0.7)
					(thickness 0.15)
				)
				(justify left bottom)
			)
		)
		(fp_text user "Author: Antmicro"
			(at -1.9 5.947 270)
			(layer "F.Fab")
			(effects
				(font
					(size 0.7 0.7)
					(thickness 0.15)
				)
				(justify left bottom)
			)
		)
		(pad "1" smd roundrect
			(at -1.1 0 270)
			(size 1.2 1.3)
			(layers "F.Cu" "F.Mask" "F.Paste")
			(roundrect_rratio 0.25)
			(net 23 "GND")
			(pintype "passive")
		)
		(pad "2" smd roundrect
			(at 1.1 0 270)
			(size 1.2 1.3)
			(layers "F.Cu" "F.Mask" "F.Paste")
			(roundrect_rratio 0.25)
			(net 349 "/Power input/5V_OUT")
			(pintype "passive")
		)
	)
	(footprint "antmicro-footprints:Fiducial_1mm_Mask2mm"
		(layer "F.Cu")
		(at 127 145)
		(descr "Circular Fiducial, 1mm bare copper, 3mm soldermask opening")
		(tags "fiducial")
		(property "Reference" "FD5"
			(at -1 -1.4 0)
			(layer "F.SilkS")
			(effects
				(font
					(size 0.7 0.7)
					(thickness 0.15)
				)
				(justify left bottom)
			)
		)
		(property "Value" "Fiducial_1mm_Mask2mm"
			(at 0 2.2 0)
			(layer "F.Fab")
			(effects
				(font
					(size 0.7 0.7)
					(thickness 0.15)
				)
				(justify left bottom)
			)
		)
		(property "Description" "Fiducial mask"
			(at 0 0 0)
			(layer "F.Fab")
			(hide yes)
			(effects
				(font
					(size 1.27 1.27)
					(thickness 0.15)
				)
			)
		)
		(property "Author" "Antmicro"
			(at 0 0 0)
			(unlocked yes)
			(layer "F.Fab")
			(hide yes)
			(effects
				(font
					(size 1 1)
					(thickness 0.15)
				)
			)
		)
		(property "License" "Apache-2.0"
			(at 0 0 0)
			(unlocked yes)
			(layer "F.Fab")
			(hide yes)
			(effects
				(font
					(size 1 1)
					(thickness 0.15)
				)
			)
		)
		(sheetname "/")
		(sheetfile "thunderbolt-to-10gbe-adapter.kicad_sch")
		(attr exclude_from_pos_files exclude_from_bom)
		(fp_circle
			(center 0 0)
			(end 1.24 0)
			(stroke
				(width 0.05)
				(type solid)
			)
			(fill no)
			(layer "F.CrtYd")
		)
		(fp_circle
			(center 0 0)
			(end 0.999 0)
			(stroke
				(width 0.15)
				(type solid)
			)
			(fill no)
			(layer "F.Fab")
		)
		(fp_text user "Author: Antmicro"
			(at -1.25 5.803 0)
			(layer "F.Fab")
			(effects
				(font
					(size 0.7 0.7)
					(thickness 0.15)
				)
				(justify left bottom)
			)
		)
		(fp_text user "${REFERENCE}"
			(at -1.25 4.603 0)
			(layer "F.Fab")
			(effects
				(font
					(size 0.7 0.7)
					(thickness 0.15)
				)
				(justify left bottom)
			)
		)
		(fp_text user "License: Apache-2.0"
			(at -1.25 7.003 0)
			(layer "F.Fab")
			(effects
				(font
					(size 0.7 0.7)
					(thickness 0.15)
				)
				(justify left bottom)
			)
		)
		(pad "" smd circle
			(at 0 0)
			(size 1 1)
			(layers "F.Cu" "F.Mask")
			(solder_mask_margin 0.5)
			(clearance 0.5)
		)
	)
	(footprint "antmicro-footprints:C_0603_1608Metric_EIA"
		(layer "F.Cu")
		(at 137.870001 92.600003 180)
		(descr "Capacitor SMD 0603, IPC-7351 Density Level A")
		(tags "Capacitor 0603")
		(property "Reference" "C139"
			(at -37.144997 9.199999 180)
			(layer "F.SilkS")
			(effects
				(font
					(size 0.7 0.7)
					(thickness 0.15)
				)
			)
		)
		(property "Value" "C_22u_16V_0603"
			(at -1.42757 1.770288 180)
			(layer "F.Fab")
			(effects
				(font
					(size 0.7 0.7)
					(thickness 0.15)
				)
				(justify left bottom)
			)
		)
		(property "Datasheet" "https://product.samsungsem.com/mlcc/CL10A226MO7JZN.do"
			(at 0 0 180)
			(layer "F.Fab")
			(hide yes)
			(effects
				(font
					(size 1.27 1.27)
					(thickness 0.15)
				)
			)
		)
		(property "Description" "SMD Multilayer Ceramic Capacitor"
			(at 0 0 180)
			(layer "F.Fab")
			(hide yes)
			(effects
				(font
					(size 1.27 1.27)
					(thickness 0.15)
				)
			)
		)
		(property "MPN" "CL10A226MO7JZNC"
			(at 0 0 180)
			(unlocked yes)
			(layer "F.Fab")
			(hide yes)
			(effects
				(font
					(size 1 1)
					(thickness 0.15)
				)
			)
		)
		(property "Manufacturer" "Samsung Electro-Mechanics"
			(at 0 0 180)
			(unlocked yes)
			(layer "F.Fab")
			(hide yes)
			(effects
				(font
					(size 1 1)
					(thickness 0.15)
				)
			)
		)
		(property "License" "Apache-2.0"
			(at 0 0 180)
			(unlocked yes)
			(layer "F.Fab")
			(hide yes)
			(effects
				(font
					(size 1 1)
					(thickness 0.15)
				)
			)
		)
		(property "Author" "Antmicro"
			(at 0 0 180)
			(unlocked yes)
			(layer "F.Fab")
			(hide yes)
			(effects
				(font
					(size 1 1)
					(thickness 0.15)
				)
			)
		)
		(property "Val" "22u"
			(at 0 0 180)
			(unlocked yes)
			(layer "F.Fab")
			(hide yes)
			(effects
				(font
					(size 1 1)
					(thickness 0.15)
				)
			)
		)
		(property "Voltage" "16V"
			(at 0 0 180)
			(unlocked yes)
			(layer "F.Fab")
			(hide yes)
			(effects
				(font
					(size 1 1)
					(thickness 0.15)
				)
			)
		)
		(property "Dielectric" ""
			(at 0 0 180)
			(unlocked yes)
			(layer "F.Fab")
			(hide yes)
			(effects
				(font
					(size 1 1)
					(thickness 0.15)
				)
			)
		)
		(sheetname "/X710 DCDC converters/")
		(sheetfile "DCDC_converters_X710.kicad_sch")
		(attr smd)
		(fp_line
			(start -0.15 0.55)
			(end 0.15 0.55)
			(stroke
				(width 0.15)
				(type solid)
			)
			(layer "F.SilkS")
		)
		(fp_line
			(start -0.15 -0.55)
			(end 0.15 -0.55)
			(stroke
				(width 0.15)
				(type solid)
			)
			(layer "F.SilkS")
		)
		(fp_rect
			(start -1.25 -0.65)
			(end 1.25 0.65)
			(stroke
				(width 0.05)
				(type solid)
			)
			(fill no)
			(layer "F.CrtYd")
		)
		(fp_rect
			(start -0.8 -0.45)
			(end 0.8 0.45)
			(stroke
				(width 0.15)
				(type solid)
			)
			(fill no)
			(layer "F.Fab")
		)
		(fp_text user "License: Apache-2.0"
			(at -1.682 5.895 180)
			(layer "F.Fab")
			(effects
				(font
					(size 0.7 0.7)
					(thickness 0.15)
				)
				(justify left bottom)
			)
		)
		(fp_text user "Author: Antmicro"
			(at -1.682 4.894 180)
			(layer "F.Fab")
			(effects
				(font
					(size 0.7 0.7)
					(thickness 0.15)
				)
				(justify left bottom)
			)
		)
		(fp_text user "${REFERENCE}"
			(at -1.682 3.895 180)
			(layer "F.Fab")
			(effects
				(font
					(size 0.7 0.7)
					(thickness 0.15)
				)
				(justify left bottom)
			)
		)
		(pad "1" smd roundrect
			(at -0.7 0 180)
			(size 0.8 1.1)
			(layers "F.Cu" "F.Mask" "F.Paste")
			(roundrect_rratio 0.2)
			(net 23 "GND")
			(pintype "passive")
		)
		(pad "2" smd roundrect
			(at 0.7 0 180)
			(size 0.8 1.1)
			(layers "F.Cu" "F.Mask" "F.Paste")
			(roundrect_rratio 0.2)
			(net 334 "/X710 DCDC converters/+3V3_OUT")
			(pintype "passive")
		)
	)
	(footprint "antmicro-footprints:R_0402_1005Metric"
		(layer "F.Cu")
		(at 154.304999 65.174999 90)
		(descr "Resistor SMD 0402")
		(tags "resistor SMD 0402")
		(property "Reference" "R148"
			(at 2.374999 0.095001 90)
			(layer "F.SilkS")
			(effects
				(font
					(size 0.7 0.7)
					(thickness 0.15)
				)
			)
		)
		(property "Value" "R_100k_0402"
			(at -1.011843 1.772047 90)
			(layer "F.Fab")
			(effects
				(font
					(size 0.7 0.7)
					(thickness 0.15)
				)
				(justify left bottom)
			)
		)
		(property "Datasheet" "https://www.bourns.com/docs/product-datasheets/cr.pdf"
			(at 0 0 90)
			(layer "F.Fab")
			(hide yes)
			(effects
				(font
					(size 1.27 1.27)
					(thickness 0.15)
				)
			)
		)
		(property "Description" "SMD Chip Resistor, 100 kohm, ± 1%, 62.5 mW, 0402 [1005 Metric], Thick Film, General Purpose"
			(at 0 0 90)
			(layer "F.Fab")
			(hide yes)
			(effects
				(font
					(size 1.27 1.27)
					(thickness 0.15)
				)
			)
		)
		(property "MPN" "CR0402-FX-1003GLF"
			(at 0 0 90)
			(unlocked yes)
			(layer "F.Fab")
			(hide yes)
			(effects
				(font
					(size 1 1)
					(thickness 0.15)
				)
			)
		)
		(property "Manufacturer" "Bourns"
			(at 0 0 90)
			(unlocked yes)
			(layer "F.Fab")
			(hide yes)
			(effects
				(font
					(size 1 1)
					(thickness 0.15)
				)
			)
		)
		(property "License" "Apache-2.0"
			(at 0 0 90)
			(unlocked yes)
			(layer "F.Fab")
			(hide yes)
			(effects
				(font
					(size 1 1)
					(thickness 0.15)
				)
			)
		)
		(property "Author" "Antmicro"
			(at 0 0 90)
			(unlocked yes)
			(layer "F.Fab")
			(hide yes)
			(effects
				(font
					(size 1 1)
					(thickness 0.15)
				)
			)
		)
		(property "Val" "100k"
			(at 0 0 90)
			(unlocked yes)
			(layer "F.Fab")
			(hide yes)
			(effects
				(font
					(size 1 1)
					(thickness 0.15)
				)
			)
		)
		(property "Tolerance" "1%"
			(at 0 0 90)
			(unlocked yes)
			(layer "F.Fab")
			(hide yes)
			(effects
				(font
					(size 1 1)
					(thickness 0.15)
				)
			)
		)
		(sheetname "/X710-AT2 Misc/")
		(sheetfile "x710-at2-mics.kicad_sch")
		(attr smd)
		(fp_rect
			(start -0.925 -0.47)
			(end 0.925 0.47)
			(stroke
				(width 0.05)
				(type default)
			)
			(fill no)
			(layer "F.CrtYd")
		)
		(fp_rect
			(start -0.5 -0.25)
			(end 0.5 0.25)
			(stroke
				(width 0.15)
				(type solid)
			)
			(fill no)
			(layer "F.Fab")
		)
		(fp_text user "License: Apache-2.0"
			(at -0.95 5.169 90)
			(layer "F.Fab")
			(effects
				(font
					(size 0.7 0.7)
					(thickness 0.15)
				)
				(justify left bottom)
			)
		)
		(fp_text user "${REFERENCE}"
			(at -0.95 3.168 90)
			(layer "F.Fab")
			(effects
				(font
					(size 0.7 0.7)
					(thickness 0.15)
				)
				(justify left bottom)
			)
		)
		(fp_text user "Author: Antmicro"
			(at -0.95 4.169 90)
			(layer "F.Fab")
			(effects
				(font
					(size 0.7 0.7)
					(thickness 0.15)
				)
				(justify left bottom)
			)
		)
		(pad "1" smd roundrect
			(at -0.48 0 90)
			(size 0.59 0.64)
			(layers "F.Cu" "F.Mask" "F.Paste")
			(roundrect_rratio 0.25)
			(net 23 "GND")
			(pintype "passive")
		)
		(pad "2" smd roundrect
			(at 0.48 0 90)
			(size 0.59 0.64)
			(layers "F.Cu" "F.Mask" "F.Paste")
			(roundrect_rratio 0.25)
			(net 143 "/X710-AT2 Misc/NCSI.TX_EN")
			(pintype "passive")
		)
	)
)
